# BASEBOARD_FAB2 (Tioga Pass) — schematic netlist excerpt (pin names and nets, part order shuffled) for the footprints in the layout excerpt that follows; sources: Cadence DE-HDL packaged netlist, KiCad conversion of Wiwynn_Tioga_Pass_MB.brd

T1P2  TPAD-DIFF-4P-GP  pkg DISCRET-GB3  page 256
  \1\  = L3_85OHM_6INCH_DP
  \2\  = L3_85OHM_6INCH_DN
  GND1  = GND
  GND2  = GND

R1T23  RES  0.0 5% EMPTY  pkg 0402  page 145 : A = FM_BMC_ONCTL_R_N ; B = GND

(kicad_pcb
	(version 20260206)
	(generator "pcbnew")
	(generator_version "10.0")
	(general
		(thickness 1.6)
		(legacy_teardrops no)
	)
	(paper "A4")
	(title_block
		(title "Wiwynn_Tioga_Pass_MB.brd")
		(comment 1 "Tioga Pass / footprints 509-510 of 4770")
	)
	(layers
		(0 "F.Cu" signal "TOP")
		(4 "In1.Cu" signal "L2GND")
		(6 "In2.Cu" signal "L3")
		(8 "In3.Cu" signal "L4GND")
		(10 "In4.Cu" signal "L5")
		(12 "In5.Cu" signal "L6GND")
		(14 "In6.Cu" signal "L7VCC")
		(16 "In7.Cu" signal "L8VCC")
		(18 "In8.Cu" signal "L9GND")
		(20 "In9.Cu" signal "L10")
		(22 "In10.Cu" signal "L11GND")
		(24 "In11.Cu" signal "L12")
		(26 "In12.Cu" signal "L13GND")
		(2 "B.Cu" signal "BOTTOM")
		(9 "F.Adhes" user "F.Adhesive")
		(11 "B.Adhes" user "B.Adhesive")
		(13 "F.Paste" user "Package Geometry/Pastemask Top")
		(15 "B.Paste" user "Package Geometry/Pastemask Bottom")
		(5 "F.SilkS" user "Ref Des/Silkscreen Top")
		(7 "B.SilkS" user "Ref Des/Silkscreen Bottom")
		(1 "F.Mask" user "Board Geometry/Soldermask Top")
		(3 "B.Mask" user "Board Geometry/Soldermask Bottom")
		(17 "Dwgs.User" user "User.Drawings")
		(19 "Cmts.User" user "User.Comments")
		(21 "Eco1.User" user "User.Eco1")
		(23 "Eco2.User" user "User.Eco2")
		(25 "Edge.Cuts" user "Board Geometry/Outline")
		(27 "Margin" user)
		(31 "F.CrtYd" user "Package Geometry/Place Bound Top")
		(29 "B.CrtYd" user "Package Geometry/Place Bound Bottom")
		(35 "F.Fab" user "Ref Des/Assembly Top")
		(33 "B.Fab" user "Ref Des/Assembly Bottom")
	)
	(footprint ""
		(layer "F.Cu")
		(at 206.751936 11.952478 -90)
		(property "Reference" "T1P2"
			(at 0 0 270)
			(layer "F.SilkS")
			(hide yes)
			(effects
				(font
					(size 1.27 1.27)
				)
			)
		)
		(property "Value" "*"
			(at -3.302 1.12395 270)
			(unlocked yes)
			(layer "F.Fab")
			(hide yes)
			(effects
				(font
					(size 0.889 0.889)
					(thickness 0.1524)
				)
			)
		)
		(property "Device Type" "TPAD-DIFF-4P-GP_DISCRET-GB3-TPA"
			(at -3.302 -0.40005 270)
			(unlocked yes)
			(layer "F.Fab")
			(hide yes)
			(effects
				(font
					(size 0.889 0.889)
					(thickness 0.1524)
				)
			)
		)
		(duplicate_pad_numbers_are_jumpers no)
		(fp_line
			(start -2.286 2.286)
			(end 2.286 2.286)
			(stroke
				(width 0.1524)
				(type default)
			)
			(layer "F.SilkS")
		)
		(fp_line
			(start 2.286 2.286)
			(end 2.286 -2.286)
			(stroke
				(width 0.1524)
				(type default)
			)
			(layer "F.SilkS")
		)
		(fp_line
			(start -2.286 -2.286)
			(end -2.286 2.286)
			(stroke
				(width 0.1524)
				(type default)
			)
			(layer "F.SilkS")
		)
		(fp_line
			(start 2.286 -2.286)
			(end -2.286 -2.286)
			(stroke
				(width 0.1524)
				(type default)
			)
			(layer "F.SilkS")
		)
		(fp_line
			(start -2.413 -2.413)
			(end -2.413 -1.143)
			(stroke
				(width 0.4064)
				(type default)
			)
			(layer "F.SilkS")
		)
		(fp_line
			(start -1.143 -2.413)
			(end -2.413 -2.413)
			(stroke
				(width 0.4064)
				(type default)
			)
			(layer "F.SilkS")
		)
		(fp_rect
			(start -2.54 2.54)
			(end 2.54 -2.54)
			(stroke
				(width 0)
				(type default)
			)
			(fill no)
			(layer "F.CrtYd")
		)
		(fp_rect
			(start -2.54 2.54)
			(end 2.54 -2.54)
			(stroke
				(width 0)
				(type default)
			)
			(fill no)
			(layer "F.Fab")
		)
		(pad "1" thru_hole circle
			(at -1.27 -1.27 270)
			(size 1.524 1.524)
			(drill 0.9144)
			(layers "*.Cu" "*.Mask")
			(remove_unused_layers no)
			(net "L3_85OHM_6INCH_DP")
			(clearance -0.0508)
			(thermal_gap 0.127)
			(padstack
				(mode front_inner_back)
				(layer "Inner"
					(shape circle)
					(size 1.1684 1.1684)
					(clearance 0.127)
				)
				(layer "B.Cu"
					(shape circle)
					(size 1.524 1.524)
					(clearance -0.0508)
				)
			)
		)
		(pad "2" thru_hole circle
			(at 1.27 -1.27 270)
			(size 1.524 1.524)
			(drill 0.9144)
			(layers "*.Cu" "*.Mask")
			(remove_unused_layers no)
			(net "L3_85OHM_6INCH_DN")
			(clearance -0.0508)
			(thermal_gap 0.127)
			(padstack
				(mode front_inner_back)
				(layer "Inner"
					(shape circle)
					(size 1.1684 1.1684)
					(clearance 0.127)
				)
				(layer "B.Cu"
					(shape circle)
					(size 1.524 1.524)
					(clearance -0.0508)
				)
			)
		)
		(pad "GND1" thru_hole rect
			(at -1.27 1.27 270)
			(size 1.524 1.524)
			(drill 0.9144)
			(layers "*.Cu" "*.Mask")
			(remove_unused_layers no)
			(net "GND")
			(clearance -0.0508)
			(thermal_gap 0.127)
			(padstack
				(mode front_inner_back)
				(layer "Inner"
					(shape circle)
					(size 1.1684 1.1684)
					(clearance 0.127)
				)
				(layer "B.Cu"
					(shape rect)
					(size 1.524 1.524)
					(clearance -0.0508)
				)
			)
		)
		(pad "GND2" thru_hole rect
			(at 1.27 1.27 270)
			(size 1.524 1.524)
			(drill 0.9144)
			(layers "*.Cu" "*.Mask")
			(remove_unused_layers no)
			(net "GND")
			(clearance -0.0508)
			(thermal_gap 0.127)
			(padstack
				(mode front_inner_back)
				(layer "Inner"
					(shape circle)
					(size 1.1684 1.1684)
					(clearance 0.127)
				)
				(layer "B.Cu"
					(shape rect)
					(size 1.524 1.524)
					(clearance -0.0508)
				)
			)
		)
	)
	(footprint ""
		(layer "F.Cu")
		(at 419.316408 -48.064166 180)
		(property "Reference" "R1T23"
			(at -0.8382 -0.67818 180)
			(unlocked yes)
			(layer "F.SilkS")
			(effects
				(font
					(size 0.4064 0.254)
					(thickness 0.1524)
				)
				(justify left)
			)
		)
		(property "Value" ""
			(at 0 0 180)
			(layer "F.Fab")
			(effects
				(font
					(size 1.27 1.27)
				)
			)
		)
		(duplicate_pad_numbers_are_jumpers no)
		(fp_poly
			(pts
				(xy -0.2794 -0.1016) (xy 0.2794 -0.1016) (xy 0.2794 0.9906) (xy -0.2794 0.9906)
			)
			(stroke
				(width 0)
				(type default)
			)
			(fill no)
			(layer "F.CrtYd")
		)
		(fp_line
			(start 0.2794 0.9906)
			(end 0.2794 -0.1016)
			(stroke
				(width 0.1)
				(type default)
			)
			(layer "F.Fab")
		)
		(fp_line
			(start 0.2794 -0.1016)
			(end -0.2794 -0.1016)
			(stroke
				(width 0.1)
				(type default)
			)
			(layer "F.Fab")
		)
		(fp_line
			(start -0.2794 0.9906)
			(end 0.2794 0.9906)
			(stroke
				(width 0.1)
				(type default)
			)
			(layer "F.Fab")
		)
		(fp_line
			(start -0.2794 -0.1016)
			(end -0.2794 0.9906)
			(stroke
				(width 0.1)
				(type default)
			)
			(layer "F.Fab")
		)
		(pad "1" smd rect
			(at 0 0 180)
			(size 0.508 0.508)
			(layers "F.Cu" "F.Mask" "F.Paste")
			(net "FM_BMC_ONCTL_R_N")
		)
		(pad "2" smd rect
			(at 0 0.889 180)
			(size 0.508 0.508)
			(layers "F.Cu" "F.Mask" "F.Paste")
			(net "GND")
		)
		(zone
			(layer "F.Cu")
			(hatch none 0.5)
			(connect_pads
				(clearance 0)
			)
			(min_thickness 0.25)
			(keepout
				(tracks not_allowed)
				(vias allowed)
				(pads allowed)
				(copperpour not_allowed)
				(footprints allowed)
			)
			(placement
				(enabled no)
				(sheetname "")
			)
			(fill
				(thermal_gap 0.5)
				(thermal_bridge_width 0.5)
				(island_removal_mode 0)
			)
			(polygon
				(pts
					(xy 419.570408 -48.699166) (xy 419.062408 -48.699166) (xy 419.062408 -48.318166) (xy 419.570408 -48.318166)
				)
			)
		)
		(zone
			(layer "F.Cu")
			(hatch none 0.5)
			(connect_pads
				(clearance 0)
			)
			(min_thickness 0.25)
			(keepout
				(tracks allowed)
				(vias not_allowed)
				(pads allowed)
				(copperpour not_allowed)
				(footprints allowed)
			)
			(placement
				(enabled no)
				(sheetname "")
			)
			(fill
				(thermal_gap 0.5)
				(thermal_bridge_width 0.5)
				(island_removal_mode 0)
			)
			(polygon
				(pts
					(xy 419.570408 -48.318166) (xy 419.062408 -48.318166) (xy 419.062408 -48.699166) (xy 419.570408 -48.699166)
				)
			)
		)
	)
)
